# TIMECARD (Time Appliance Project (Time Card)) — schematic netlist excerpt (pin names and nets, part order shuffled) for the footprints in the layout excerpt that follows; sources: Cadence DE-HDL packaged netlist, KiCad conversion of R4006-B0001-02_R01.brd

C279  CAPACITOR  0.1UF 25V 10%  pkg SMC_0402R_H022  page 20 : \1\ = XP3R3V_FPGA ; \2\ = SG
C247  CAPACITOR  10UF 6.3V 20%  pkg SMC_0402R_H022  page 15 : \1\ = VDD3V3_OSC_125M ; \2\ = SG

(kicad_pcb
	(version 20260206)
	(generator "pcbnew")
	(generator_version "10.0")
	(general
		(thickness 1.6)
		(legacy_teardrops no)
	)
	(paper "A4")
	(title_block
		(title "timecard-production-celestica-r4006 — R4006-B0001-02_R01.brd")
		(comment 1 "Time Appliance Project (Time Card) / footprints 120-121 of 1113")
	)
	(layers
		(0 "F.Cu" signal "TOP")
		(4 "In1.Cu" signal "L02_GND1")
		(6 "In2.Cu" signal "L03_SIG1")
		(8 "In3.Cu" signal "L04_GND2")
		(10 "In4.Cu" signal "L05_VCC1")
		(12 "In5.Cu" signal "L06_VCC2")
		(14 "In6.Cu" signal "L07_GND3")
		(16 "In7.Cu" signal "L08_SIG2")
		(18 "In8.Cu" signal "L09_GND4")
		(2 "B.Cu" signal "BOTTOM")
		(9 "F.Adhes" user "F.Adhesive")
		(11 "B.Adhes" user "B.Adhesive")
		(13 "F.Paste" user "Package Geometry/Pastemask Top")
		(15 "B.Paste" user "Package Geometry/Pastemask Bottom")
		(5 "F.SilkS" user "Ref Des/Silkscreen Top")
		(7 "B.SilkS" user "Ref Des/Silkscreen Bottom")
		(1 "F.Mask" user "Board Geometry/Soldermask Top")
		(3 "B.Mask" user "Board Geometry/Soldermask Bottom")
		(17 "Dwgs.User" user "User.Drawings")
		(19 "Cmts.User" user "User.Comments")
		(21 "Eco1.User" user "User.Eco1")
		(23 "Eco2.User" user "User.Eco2")
		(25 "Edge.Cuts" user "Board Geometry/Outline")
		(27 "Margin" user)
		(31 "F.CrtYd" user "Package Geometry/Place Bound Top")
		(29 "B.CrtYd" user "Package Geometry/Place Bound Bottom")
		(35 "F.Fab" user "Ref Des/Assembly Top")
		(33 "B.Fab" user "Ref Des/Assembly Bottom")
	)
	(footprint ""
		(layer "F.Cu")
		(at 96.266 -24.638 180)
		(property "Reference" "C247"
			(at 12.065 -0.29337 0)
			(unlocked yes)
			(layer "F.SilkS")
			(effects
				(font
					(size 0.7874 0.5842)
					(thickness 0.1524)
				)
			)
		)
		(property "Value" "VAL*"
			(at 0.0762 2.067306 180)
			(unlocked yes)
			(layer "F.Fab")
			(hide yes)
			(effects
				(font
					(size 0.7874 0.5842)
					(thickness 0.1524)
				)
			)
		)
		(property "Tolerance" "TOL*"
			(at 0.0762 3.032506 180)
			(unlocked yes)
			(layer "Cmts.User")
			(hide yes)
			(effects
				(font
					(size 0.7874 0.5842)
					(thickness 0.1524)
				)
			)
		)
		(property "User Part Number" "PARTNUM*"
			(at 0.1016 4.023106 180)
			(unlocked yes)
			(layer "Cmts.User")
			(hide yes)
			(effects
				(font
					(size 0.7874 0.5842)
					(thickness 0.1524)
				)
			)
		)
		(property "Device Type" "CAPACITOR-G105-0C106-BM,10UF,2A"
			(at 0.0508 1.127506 180)
			(unlocked yes)
			(layer "F.Fab")
			(hide yes)
			(effects
				(font
					(size 0.7874 0.5842)
					(thickness 0.1524)
				)
			)
		)
		(duplicate_pad_numbers_are_jumpers no)
		(fp_line
			(start 1.143 0.5588)
			(end 1.143 -0.5588)
			(stroke
				(width 0.1)
				(type default)
			)
			(layer "F.SilkS")
		)
		(fp_line
			(start 1.143 -0.5588)
			(end -1.143 -0.5588)
			(stroke
				(width 0.1)
				(type default)
			)
			(layer "F.SilkS")
		)
		(fp_line
			(start -1.143 0.5588)
			(end 1.143 0.5588)
			(stroke
				(width 0.1)
				(type default)
			)
			(layer "F.SilkS")
		)
		(fp_line
			(start -1.143 -0.5588)
			(end -1.143 0.5588)
			(stroke
				(width 0.1)
				(type default)
			)
			(layer "F.SilkS")
		)
		(fp_rect
			(start 1.143 -0.5588)
			(end -1.143 0.5588)
			(stroke
				(width 0)
				(type default)
			)
			(fill no)
			(layer "F.CrtYd")
		)
		(fp_line
			(start 0.508 0.3048)
			(end 0.508 -0.3048)
			(stroke
				(width 0.1)
				(type default)
			)
			(layer "F.Fab")
		)
		(fp_line
			(start 0.508 -0.3048)
			(end -0.508 -0.3048)
			(stroke
				(width 0.1)
				(type default)
			)
			(layer "F.Fab")
		)
		(fp_line
			(start -0.508 0.3048)
			(end 0.508 0.3048)
			(stroke
				(width 0.1)
				(type default)
			)
			(layer "F.Fab")
		)
		(fp_line
			(start -0.508 -0.3048)
			(end -0.508 0.3048)
			(stroke
				(width 0.1)
				(type default)
			)
			(layer "F.Fab")
		)
		(pad "1" smd rect
			(at -0.5334 0 180)
			(size 0.7112 0.6096)
			(layers "F.Cu" "F.Mask" "F.Paste")
			(net "VDD3V3_OSC_125M")
		)
		(pad "2" smd rect
			(at 0.5334 0 180)
			(size 0.7112 0.6096)
			(layers "F.Cu" "F.Mask" "F.Paste")
			(net "SG")
		)
		(zone
			(layer "F.Cu")
			(hatch none 0.5)
			(connect_pads
				(clearance 0)
			)
			(min_thickness 0.25)
			(keepout
				(tracks allowed)
				(vias not_allowed)
				(pads allowed)
				(copperpour not_allowed)
				(footprints allowed)
			)
			(placement
				(enabled no)
				(sheetname "")
			)
			(fill
				(thermal_gap 0.5)
				(thermal_bridge_width 0.5)
				(island_removal_mode 0)
			)
			(polygon
				(pts
					(xy 96.1898 -24.3332) (xy 96.3422 -24.3332) (xy 96.3422 -24.9428) (xy 96.1898 -24.9428)
				)
			)
		)
	)
	(footprint ""
		(layer "F.Cu")
		(at 90.0684 -64.3636 -90)
		(property "Reference" "C279"
			(at -13.1064 9.63803 90)
			(unlocked yes)
			(layer "F.SilkS")
			(effects
				(font
					(size 0.7874 0.5842)
					(thickness 0.1524)
				)
			)
		)
		(property "Value" "VAL*"
			(at 0.0762 2.067306 270)
			(unlocked yes)
			(layer "F.Fab")
			(hide yes)
			(effects
				(font
					(size 0.7874 0.5842)
					(thickness 0.1524)
				)
			)
		)
		(property "Device Type" "CAPACITOR-G105-0B104-EK,0.1UF,A"
			(at 0.0508 1.127506 270)
			(unlocked yes)
			(layer "F.Fab")
			(hide yes)
			(effects
				(font
					(size 0.7874 0.5842)
					(thickness 0.1524)
				)
			)
		)
		(property "User Part Number" "PARTNUM*"
			(at 0.1016 4.023106 270)
			(unlocked yes)
			(layer "Cmts.User")
			(hide yes)
			(effects
				(font
					(size 0.7874 0.5842)
					(thickness 0.1524)
				)
			)
		)
		(property "Tolerance" "TOL*"
			(at 0.0762 3.032506 270)
			(unlocked yes)
			(layer "Cmts.User")
			(hide yes)
			(effects
				(font
					(size 0.7874 0.5842)
					(thickness 0.1524)
				)
			)
		)
		(duplicate_pad_numbers_are_jumpers no)
		(fp_line
			(start -1.143 0.5588)
			(end 1.143 0.5588)
			(stroke
				(width 0.1)
				(type default)
			)
			(layer "F.SilkS")
		)
		(fp_line
			(start 1.143 0.5588)
			(end 1.143 -0.5588)
			(stroke
				(width 0.1)
				(type default)
			)
			(layer "F.SilkS")
		)
		(fp_line
			(start -1.143 -0.5588)
			(end -1.143 0.5588)
			(stroke
				(width 0.1)
				(type default)
			)
			(layer "F.SilkS")
		)
		(fp_line
			(start 1.143 -0.5588)
			(end -1.143 -0.5588)
			(stroke
				(width 0.1)
				(type default)
			)
			(layer "F.SilkS")
		)
		(fp_rect
			(start 1.143 0.5588)
			(end -1.143 -0.5588)
			(stroke
				(width 0)
				(type default)
			)
			(fill no)
			(layer "F.CrtYd")
		)
		(fp_line
			(start -0.508 0.3048)
			(end 0.508 0.3048)
			(stroke
				(width 0.1)
				(type default)
			)
			(layer "F.Fab")
		)
		(fp_line
			(start 0.508 0.3048)
			(end 0.508 -0.3048)
			(stroke
				(width 0.1)
				(type default)
			)
			(layer "F.Fab")
		)
		(fp_line
			(start -0.508 -0.3048)
			(end -0.508 0.3048)
			(stroke
				(width 0.1)
				(type default)
			)
			(layer "F.Fab")
		)
		(fp_line
			(start 0.508 -0.3048)
			(end -0.508 -0.3048)
			(stroke
				(width 0.1)
				(type default)
			)
			(layer "F.Fab")
		)
		(pad "1" smd rect
			(at -0.5334 0 270)
			(size 0.7112 0.6096)
			(layers "F.Cu" "F.Mask" "F.Paste")
			(net "XP3R3V_FPGA")
		)
		(pad "2" smd rect
			(at 0.5334 0 270)
			(size 0.7112 0.6096)
			(layers "F.Cu" "F.Mask" "F.Paste")
			(net "SG")
		)
		(zone
			(layer "F.Cu")
			(hatch none 0.5)
			(connect_pads
				(clearance 0)
			)
			(min_thickness 0.25)
			(keepout
				(tracks allowed)
				(vias not_allowed)
				(pads allowed)
				(copperpour not_allowed)
				(footprints allowed)
			)
			(placement
				(enabled no)
				(sheetname "")
			)
			(fill
				(thermal_gap 0.5)
				(thermal_bridge_width 0.5)
				(island_removal_mode 0)
			)
			(polygon
				(pts
					(xy 89.7636 -64.2874) (xy 90.3732 -64.2874) (xy 90.3732 -64.4398) (xy 89.7636 -64.4398)
				)
			)
		)
	)
)
